# S9S_MB_2U (Grand Teton) — schematic netlist excerpt (pin names and nets, part order shuffled) for the footprints in the layout excerpt that follows; sources: Cadence DE-HDL packaged netlist, KiCad conversion of 03242023_DA0F0TMBIJ0_F0T_Motherboard_J_brd_V01_OCP.brd

R175  Q_RES  100 1% CHIP  pkg 0402LF  page 124 : A = PWRGD_DRAMPWRGD_CPU0_AB_LVC1_R2 ; B = PVCCD_HV_CPU0
R70  Q_RES  10K 1% CHIP  pkg 0402LF  page 43 : A = PWRGD_PLT_AUX_CPU1_LVT3 ; B = GND

(kicad_pcb
	(version 20260206)
	(generator "pcbnew")
	(generator_version "10.0")
	(general
		(thickness 1.6)
		(legacy_teardrops no)
	)
	(paper "A4")
	(title_block
		(title "03242023_DA0F0TMBIJ0_F0T_Motherboard_J_brd_V01_OCP.brd")
		(comment 1 "Grand Teton / footprints 5414-5415 of 6105")
	)
	(layers
		(0 "F.Cu" signal "TOP")
		(4 "In1.Cu" signal "GND")
		(6 "In2.Cu" signal "IN1")
		(8 "In3.Cu" signal "GND1")
		(10 "In4.Cu" signal "IN2")
		(12 "In5.Cu" signal "GND2")
		(14 "In6.Cu" signal "IN3")
		(16 "In7.Cu" signal "GND3")
		(18 "In8.Cu" signal "VCC")
		(20 "In9.Cu" signal "VCC1")
		(22 "In10.Cu" signal "GND4")
		(24 "In11.Cu" signal "IN4")
		(26 "In12.Cu" signal "GND5")
		(28 "In13.Cu" signal "IN5")
		(30 "In14.Cu" signal "GND6")
		(32 "In15.Cu" signal "IN6")
		(34 "In16.Cu" signal "GND7")
		(2 "B.Cu" signal "BOTTOM")
		(9 "F.Adhes" user "F.Adhesive")
		(11 "B.Adhes" user "B.Adhesive")
		(13 "F.Paste" user "Package Geometry/Pastemask Top")
		(15 "B.Paste" user "Package Geometry/Pastemask Bottom")
		(5 "F.SilkS" user "Ref Des/Silkscreen Top")
		(7 "B.SilkS" user "Ref Des/Silkscreen Bottom")
		(1 "F.Mask" user "Board Geometry/Soldermask Top")
		(3 "B.Mask" user "Board Geometry/Soldermask Bottom")
		(17 "Dwgs.User" user "User.Drawings")
		(19 "Cmts.User" user "User.Comments")
		(21 "Eco1.User" user "User.Eco1")
		(23 "Eco2.User" user "User.Eco2")
		(25 "Edge.Cuts" user "Board Geometry/Outline")
		(27 "Margin" user)
		(31 "F.CrtYd" user "Package Geometry/Place Bound Top")
		(29 "B.CrtYd" user "Package Geometry/Place Bound Bottom")
		(35 "F.Fab" user "Ref Des/Assembly Top")
		(33 "B.Fab" user "Ref Des/Assembly Bottom")
	)
	(footprint ""
		(layer "B.Cu")
		(at 156.1465 -194.55511 -90)
		(property "Reference" "R70"
			(at 0 0 90)
			(layer "B.SilkS")
			(hide yes)
			(effects
				(font
					(size 1.27 1.27)
				)
				(justify mirror)
			)
		)
		(property "Value" ""
			(at 0 0 90)
			(layer "B.Fab")
			(effects
				(font
					(size 1.27 1.27)
				)
				(justify mirror)
			)
		)
		(duplicate_pad_numbers_are_jumpers no)
		(fp_line
			(start -0.7874 0.4064)
			(end 0.7874 0.4064)
			(stroke
				(width 0.1524)
				(type default)
			)
			(layer "B.SilkS")
		)
		(fp_line
			(start 0.7874 0.4064)
			(end 0.7874 -0.4064)
			(stroke
				(width 0.1524)
				(type default)
			)
			(layer "B.SilkS")
		)
		(fp_line
			(start -0.7874 -0.4064)
			(end -0.7874 0.4064)
			(stroke
				(width 0.1524)
				(type default)
			)
			(layer "B.SilkS")
		)
		(fp_line
			(start 0.7874 -0.4064)
			(end -0.7874 -0.4064)
			(stroke
				(width 0.1524)
				(type default)
			)
			(layer "B.SilkS")
		)
		(fp_line
			(start -0.67945 0.3048)
			(end -0.120396 0.3048)
			(stroke
				(width 0.1)
				(type default)
			)
			(layer "B.Fab")
		)
		(fp_line
			(start -0.120396 0.3048)
			(end -0.120396 0.2794)
			(stroke
				(width 0.1)
				(type default)
			)
			(layer "B.Fab")
		)
		(fp_line
			(start 0.12065 0.3048)
			(end 0.67945 0.3048)
			(stroke
				(width 0.1)
				(type default)
			)
			(layer "B.Fab")
		)
		(fp_line
			(start 0.67945 0.3048)
			(end 0.67945 -0.305054)
			(stroke
				(width 0.1)
				(type default)
			)
			(layer "B.Fab")
		)
		(fp_line
			(start -0.120396 0.2794)
			(end 0.12065 0.2794)
			(stroke
				(width 0.1)
				(type default)
			)
			(layer "B.Fab")
		)
		(fp_line
			(start 0.12065 0.2794)
			(end 0.12065 0.3048)
			(stroke
				(width 0.1)
				(type default)
			)
			(layer "B.Fab")
		)
		(fp_line
			(start -0.12065 -0.2794)
			(end -0.12065 -0.3048)
			(stroke
				(width 0.1)
				(type default)
			)
			(layer "B.Fab")
		)
		(fp_line
			(start 0.12065 -0.2794)
			(end -0.12065 -0.2794)
			(stroke
				(width 0.1)
				(type default)
			)
			(layer "B.Fab")
		)
		(fp_line
			(start -0.67945 -0.3048)
			(end -0.67945 0.3048)
			(stroke
				(width 0.1)
				(type default)
			)
			(layer "B.Fab")
		)
		(fp_line
			(start -0.12065 -0.3048)
			(end -0.67945 -0.3048)
			(stroke
				(width 0.1)
				(type default)
			)
			(layer "B.Fab")
		)
		(fp_line
			(start 0.12065 -0.305054)
			(end 0.12065 -0.2794)
			(stroke
				(width 0.1)
				(type default)
			)
			(layer "B.Fab")
		)
		(fp_line
			(start 0.67945 -0.305054)
			(end 0.12065 -0.305054)
			(stroke
				(width 0.1)
				(type default)
			)
			(layer "B.Fab")
		)
		(pad "1" smd circle
			(at 0.40005 0 90)
			(size 0 0)
			(layers "B.Cu" "B.Mask" "B.Paste")
			(net "PWRGD_PLT_AUX_CPU1_LVT3")
		)
		(pad "2" smd circle
			(at -0.40005 0 90)
			(size 0 0)
			(layers "B.Cu" "B.Mask" "B.Paste")
			(net "GND")
		)
	)
	(footprint ""
		(layer "B.Cu")
		(at 296.183558 -194.26555 90)
		(property "Reference" "R175"
			(at 0 0 90)
			(layer "B.SilkS")
			(hide yes)
			(effects
				(font
					(size 1.27 1.27)
				)
				(justify mirror)
			)
		)
		(property "Value" ""
			(at 0 0 90)
			(layer "B.Fab")
			(effects
				(font
					(size 1.27 1.27)
				)
				(justify mirror)
			)
		)
		(duplicate_pad_numbers_are_jumpers no)
		(fp_line
			(start 0.7874 -0.4064)
			(end -0.7874 -0.4064)
			(stroke
				(width 0.1524)
				(type default)
			)
			(layer "B.SilkS")
		)
		(fp_line
			(start -0.7874 -0.4064)
			(end -0.7874 0.4064)
			(stroke
				(width 0.1524)
				(type default)
			)
			(layer "B.SilkS")
		)
		(fp_line
			(start 0.7874 0.4064)
			(end 0.7874 -0.4064)
			(stroke
				(width 0.1524)
				(type default)
			)
			(layer "B.SilkS")
		)
		(fp_line
			(start -0.7874 0.4064)
			(end 0.7874 0.4064)
			(stroke
				(width 0.1524)
				(type default)
			)
			(layer "B.SilkS")
		)
		(fp_line
			(start 0.67945 -0.305054)
			(end 0.12065 -0.305054)
			(stroke
				(width 0.1)
				(type default)
			)
			(layer "B.Fab")
		)
		(fp_line
			(start 0.12065 -0.305054)
			(end 0.12065 -0.2794)
			(stroke
				(width 0.1)
				(type default)
			)
			(layer "B.Fab")
		)
		(fp_line
			(start -0.12065 -0.3048)
			(end -0.67945 -0.3048)
			(stroke
				(width 0.1)
				(type default)
			)
			(layer "B.Fab")
		)
		(fp_line
			(start -0.67945 -0.3048)
			(end -0.67945 0.3048)
			(stroke
				(width 0.1)
				(type default)
			)
			(layer "B.Fab")
		)
		(fp_line
			(start 0.12065 -0.2794)
			(end -0.12065 -0.2794)
			(stroke
				(width 0.1)
				(type default)
			)
			(layer "B.Fab")
		)
		(fp_line
			(start -0.12065 -0.2794)
			(end -0.12065 -0.3048)
			(stroke
				(width 0.1)
				(type default)
			)
			(layer "B.Fab")
		)
		(fp_line
			(start 0.12065 0.2794)
			(end 0.12065 0.3048)
			(stroke
				(width 0.1)
				(type default)
			)
			(layer "B.Fab")
		)
		(fp_line
			(start -0.120396 0.2794)
			(end 0.12065 0.2794)
			(stroke
				(width 0.1)
				(type default)
			)
			(layer "B.Fab")
		)
		(fp_line
			(start 0.67945 0.3048)
			(end 0.67945 -0.305054)
			(stroke
				(width 0.1)
				(type default)
			)
			(layer "B.Fab")
		)
		(fp_line
			(start 0.12065 0.3048)
			(end 0.67945 0.3048)
			(stroke
				(width 0.1)
				(type default)
			)
			(layer "B.Fab")
		)
		(fp_line
			(start -0.120396 0.3048)
			(end -0.120396 0.2794)
			(stroke
				(width 0.1)
				(type default)
			)
			(layer "B.Fab")
		)
		(fp_line
			(start -0.67945 0.3048)
			(end -0.120396 0.3048)
			(stroke
				(width 0.1)
				(type default)
			)
			(layer "B.Fab")
		)
		(pad "1" smd circle
			(at 0.40005 0 270)
			(size 0 0)
			(layers "B.Cu" "B.Mask" "B.Paste")
			(net "PWRGD_DRAMPWRGD_CPU0_AB_LVC1_R2")
		)
		(pad "2" smd circle
			(at -0.40005 0 270)
			(size 0 0)
			(layers "B.Cu" "B.Mask" "B.Paste")
			(net "PVCCD_HV_CPU0")
		)
	)
)
